# T6G (Grand Teton) — schematic netlist excerpt (pin names and nets, part order shuffled) for the footprints in the layout excerpt that follows; sources: Cadence DE-HDL packaged netlist, KiCad conversion of 04192023_DAF0TMB3IC0_F0TG_MB_C_brd_V02_OCP.brd

C6064  Q_CAP  0.1UF 25V 10% X7R  pkg 0402  page 177 : A = P1V2_AUX ; B = GND
Y5  Q_CRYSTAL  32.768KHZ EMPTY  pkg SMLF  page 55 : \1\ = XTAL_CPU1_R_X32K_X1 ; \2\ = XTAL_CPU1_R_X32K_X2

(kicad_pcb
	(version 20260206)
	(generator "pcbnew")
	(generator_version "10.0")
	(general
		(thickness 1.6)
		(legacy_teardrops no)
	)
	(paper "A4")
	(title_block
		(title "04192023_DAF0TMB3IC0_F0TG_MB_C_brd_V02_OCP.brd")
		(comment 1 "Grand Teton / footprints 7797-7798 of 8354")
	)
	(layers
		(0 "F.Cu" signal "TOP")
		(4 "In1.Cu" signal "GND")
		(6 "In2.Cu" signal "IN1")
		(8 "In3.Cu" signal "GND1")
		(10 "In4.Cu" signal "IN2")
		(12 "In5.Cu" signal "GND2")
		(14 "In6.Cu" signal "IN3")
		(16 "In7.Cu" signal "GND3")
		(18 "In8.Cu" signal "VCC")
		(20 "In9.Cu" signal "VCC1")
		(22 "In10.Cu" signal "GND4")
		(24 "In11.Cu" signal "IN4")
		(26 "In12.Cu" signal "GND5")
		(28 "In13.Cu" signal "IN5")
		(30 "In14.Cu" signal "GND6")
		(32 "In15.Cu" signal "IN6")
		(34 "In16.Cu" signal "GND7")
		(2 "B.Cu" signal "BOTTOM")
		(9 "F.Adhes" user "F.Adhesive")
		(11 "B.Adhes" user "B.Adhesive")
		(13 "F.Paste" user "Package Geometry/Pastemask Top")
		(15 "B.Paste" user "Package Geometry/Pastemask Bottom")
		(5 "F.SilkS" user "Ref Des/Silkscreen Top")
		(7 "B.SilkS" user "Ref Des/Silkscreen Bottom")
		(1 "F.Mask" user "Board Geometry/Soldermask Top")
		(3 "B.Mask" user "Board Geometry/Soldermask Bottom")
		(17 "Dwgs.User" user "User.Drawings")
		(19 "Cmts.User" user "User.Comments")
		(21 "Eco1.User" user "User.Eco1")
		(23 "Eco2.User" user "User.Eco2")
		(25 "Edge.Cuts" user "Board Geometry/Outline")
		(27 "Margin" user)
		(31 "F.CrtYd" user "Package Geometry/Place Bound Top")
		(29 "B.CrtYd" user "Package Geometry/Place Bound Bottom")
		(35 "F.Fab" user "Ref Des/Assembly Top")
		(33 "B.Fab" user "Ref Des/Assembly Bottom")
	)
	(footprint ""
		(layer "B.Cu")
		(at 153.456386 -318.53505 180)
		(property "Reference" "Y5"
			(at -3.805936 0.462026 0)
			(unlocked yes)
			(layer "B.SilkS")
			(effects
				(font
					(size 0.7874 0.5842)
					(thickness 0.1524)
				)
				(justify left mirror)
			)
		)
		(property "Value" ""
			(at 0 0 0)
			(layer "B.Fab")
			(effects
				(font
					(size 1.27 1.27)
				)
				(justify mirror)
			)
		)
		(duplicate_pad_numbers_are_jumpers no)
		(fp_line
			(start 1.905 1.0414)
			(end -1.905 1.0414)
			(stroke
				(width 0.1524)
				(type default)
			)
			(layer "B.SilkS")
		)
		(fp_line
			(start 1.905 -1.0414)
			(end 1.905 1.0414)
			(stroke
				(width 0.1524)
				(type default)
			)
			(layer "B.SilkS")
		)
		(fp_line
			(start -1.905 1.0414)
			(end -1.905 -1.0414)
			(stroke
				(width 0.1524)
				(type default)
			)
			(layer "B.SilkS")
		)
		(fp_line
			(start -1.905 -1.0414)
			(end 1.905 -1.0414)
			(stroke
				(width 0.1524)
				(type default)
			)
			(layer "B.SilkS")
		)
		(fp_line
			(start 1.649984 0.824992)
			(end -1.649984 0.824992)
			(stroke
				(width 0.1)
				(type default)
			)
			(layer "B.Fab")
		)
		(fp_line
			(start 1.649984 -0.824992)
			(end 1.649984 0.824992)
			(stroke
				(width 0.1)
				(type default)
			)
			(layer "B.Fab")
		)
		(fp_line
			(start -1.649984 0.824992)
			(end -1.649984 -0.824992)
			(stroke
				(width 0.1)
				(type default)
			)
			(layer "B.Fab")
		)
		(fp_line
			(start -1.649984 -0.824992)
			(end 1.649984 -0.824992)
			(stroke
				(width 0.1)
				(type default)
			)
			(layer "B.Fab")
		)
		(pad "1" smd rect
			(at 1.249934 0)
			(size 1.016 1.8034)
			(layers "B.Cu" "B.Mask" "B.Paste")
			(net "XTAL_CPU1_R_X32K_X1")
		)
		(pad "2" smd rect
			(at -1.249934 0 180)
			(size 1.016 1.8034)
			(layers "B.Cu" "B.Mask" "B.Paste")
			(net "XTAL_CPU1_R_X32K_X2")
		)
		(zone
			(layer "B.Cu")
			(hatch none 0.5)
			(connect_pads
				(clearance 0)
			)
			(min_thickness 0.25)
			(keepout
				(tracks not_allowed)
				(vias allowed)
				(pads allowed)
				(copperpour not_allowed)
				(footprints allowed)
			)
			(placement
				(enabled no)
				(sheetname "")
			)
			(fill
				(thermal_gap 0.5)
				(thermal_bridge_width 0.5)
				(island_removal_mode 0)
			)
			(polygon
				(pts
					(xy 152.765252 -317.58255) (xy 152.765252 -319.48755) (xy 154.14752 -319.48755) (xy 154.14752 -317.58255)
				)
			)
		)
	)
	(footprint ""
		(layer "B.Cu")
		(at 130.408934 -31.622492 180)
		(property "Reference" "C6064"
			(at 0 0 0)
			(layer "B.SilkS")
			(hide yes)
			(effects
				(font
					(size 1.27 1.27)
				)
				(justify mirror)
			)
		)
		(property "Value" ""
			(at 0 0 0)
			(layer "B.Fab")
			(effects
				(font
					(size 1.27 1.27)
				)
				(justify mirror)
			)
		)
		(duplicate_pad_numbers_are_jumpers no)
		(fp_line
			(start 0.7874 0.4064)
			(end 0.7874 -0.4064)
			(stroke
				(width 0.1524)
				(type default)
			)
			(layer "B.SilkS")
		)
		(fp_line
			(start 0.7874 -0.4064)
			(end -0.7874 -0.4064)
			(stroke
				(width 0.1524)
				(type default)
			)
			(layer "B.SilkS")
		)
		(fp_line
			(start -0.7874 0.4064)
			(end 0.7874 0.4064)
			(stroke
				(width 0.1524)
				(type default)
			)
			(layer "B.SilkS")
		)
		(fp_line
			(start -0.7874 -0.4064)
			(end -0.7874 0.4064)
			(stroke
				(width 0.1524)
				(type default)
			)
			(layer "B.SilkS")
		)
		(fp_line
			(start 0.67945 0.3048)
			(end 0.67945 -0.305054)
			(stroke
				(width 0.1)
				(type default)
			)
			(layer "B.Fab")
		)
		(fp_line
			(start 0.67945 -0.305054)
			(end 0.12065 -0.305054)
			(stroke
				(width 0.1)
				(type default)
			)
			(layer "B.Fab")
		)
		(fp_line
			(start 0.12065 0.3048)
			(end 0.67945 0.3048)
			(stroke
				(width 0.1)
				(type default)
			)
			(layer "B.Fab")
		)
		(fp_line
			(start 0.12065 0.2794)
			(end 0.12065 0.3048)
			(stroke
				(width 0.1)
				(type default)
			)
			(layer "B.Fab")
		)
		(fp_line
			(start 0.12065 -0.2794)
			(end -0.12065 -0.2794)
			(stroke
				(width 0.1)
				(type default)
			)
			(layer "B.Fab")
		)
		(fp_line
			(start 0.12065 -0.305054)
			(end 0.12065 -0.2794)
			(stroke
				(width 0.1)
				(type default)
			)
			(layer "B.Fab")
		)
		(fp_line
			(start -0.120396 0.3048)
			(end -0.120396 0.2794)
			(stroke
				(width 0.1)
				(type default)
			)
			(layer "B.Fab")
		)
		(fp_line
			(start -0.120396 0.2794)
			(end 0.12065 0.2794)
			(stroke
				(width 0.1)
				(type default)
			)
			(layer "B.Fab")
		)
		(fp_line
			(start -0.12065 -0.2794)
			(end -0.12065 -0.3048)
			(stroke
				(width 0.1)
				(type default)
			)
			(layer "B.Fab")
		)
		(fp_line
			(start -0.12065 -0.3048)
			(end -0.67945 -0.3048)
			(stroke
				(width 0.1)
				(type default)
			)
			(layer "B.Fab")
		)
		(fp_line
			(start -0.67945 0.3048)
			(end -0.120396 0.3048)
			(stroke
				(width 0.1)
				(type default)
			)
			(layer "B.Fab")
		)
		(fp_line
			(start -0.67945 -0.3048)
			(end -0.67945 0.3048)
			(stroke
				(width 0.1)
				(type default)
			)
			(layer "B.Fab")
		)
		(pad "1" smd circle
			(at 0.40005 0)
			(size 0 0)
			(layers "B.Cu" "B.Mask" "B.Paste")
			(net "P1V2_AUX")
		)
		(pad "2" smd circle
			(at -0.40005 0)
			(size 0 0)
			(layers "B.Cu" "B.Mask" "B.Paste")
			(net "GND")
		)
	)
)
